# S9S_MB_2U (Grand Teton) — schematic netlist excerpt (pin names and nets, part order shuffled) for the footprints in the layout excerpt that follows; sources: Cadence DE-HDL packaged netlist, KiCad conversion of 03242023_DA0F0TMBIJ0_F0T_Motherboard_J_brd_V01_OCP.brd

C1994  Q_CAP_DIFFBUS  DIFF BUS_0.22UF 6.3V 20% X6S  pkg C0201  page 181 : \1\ = P3E_PCH_E1S_TX_DN<1> ; \2\ = P3E_PCH_E1S_TX_C_DN<1>

U369  TPS3700DDCR  EMPTY  pkg SOT23-6XF  page 306
  OUTA  = A_HSC_LOW_GATE
  GND  = GND
  \ina+\  = A_HSC_LOW
  \inb-\  = A_HSC_HIGH
  VDD  = U369_VDD
  OUTB  = HSC_D_OC

(kicad_pcb
	(version 20260206)
	(generator "pcbnew")
	(generator_version "10.0")
	(general
		(thickness 1.6)
		(legacy_teardrops no)
	)
	(paper "A4")
	(title_block
		(title "03242023_DA0F0TMBIJ0_F0T_Motherboard_J_brd_V01_OCP.brd")
		(comment 1 "Grand Teton / footprints 797-798 of 6105")
	)
	(layers
		(0 "F.Cu" signal "TOP")
		(4 "In1.Cu" signal "GND")
		(6 "In2.Cu" signal "IN1")
		(8 "In3.Cu" signal "GND1")
		(10 "In4.Cu" signal "IN2")
		(12 "In5.Cu" signal "GND2")
		(14 "In6.Cu" signal "IN3")
		(16 "In7.Cu" signal "GND3")
		(18 "In8.Cu" signal "VCC")
		(20 "In9.Cu" signal "VCC1")
		(22 "In10.Cu" signal "GND4")
		(24 "In11.Cu" signal "IN4")
		(26 "In12.Cu" signal "GND5")
		(28 "In13.Cu" signal "IN5")
		(30 "In14.Cu" signal "GND6")
		(32 "In15.Cu" signal "IN6")
		(34 "In16.Cu" signal "GND7")
		(2 "B.Cu" signal "BOTTOM")
		(9 "F.Adhes" user "F.Adhesive")
		(11 "B.Adhes" user "B.Adhesive")
		(13 "F.Paste" user "Package Geometry/Pastemask Top")
		(15 "B.Paste" user "Package Geometry/Pastemask Bottom")
		(5 "F.SilkS" user "Ref Des/Silkscreen Top")
		(7 "B.SilkS" user "Ref Des/Silkscreen Bottom")
		(1 "F.Mask" user "Board Geometry/Soldermask Top")
		(3 "B.Mask" user "Board Geometry/Soldermask Bottom")
		(17 "Dwgs.User" user "User.Drawings")
		(19 "Cmts.User" user "User.Comments")
		(21 "Eco1.User" user "User.Eco1")
		(23 "Eco2.User" user "User.Eco2")
		(25 "Edge.Cuts" user "Board Geometry/Outline")
		(27 "Margin" user)
		(31 "F.CrtYd" user "Package Geometry/Place Bound Top")
		(29 "B.CrtYd" user "Package Geometry/Place Bound Bottom")
		(35 "F.Fab" user "Ref Des/Assembly Top")
		(33 "B.Fab" user "Ref Des/Assembly Bottom")
	)
	(footprint ""
		(layer "F.Cu")
		(at 239.152684 -54.736238 180)
		(property "Reference" "C1994"
			(at 0 0 180)
			(layer "F.SilkS")
			(hide yes)
			(effects
				(font
					(size 1.27 1.27)
				)
			)
		)
		(property "Value" ""
			(at 0 0 180)
			(layer "F.Fab")
			(effects
				(font
					(size 1.27 1.27)
				)
			)
		)
		(duplicate_pad_numbers_are_jumpers no)
		(fp_line
			(start 0.299974 0.150114)
			(end -0.299974 0.150114)
			(stroke
				(width 0.1)
				(type default)
			)
			(layer "F.Fab")
		)
		(fp_line
			(start 0.299974 -0.150114)
			(end 0.299974 0.150114)
			(stroke
				(width 0.1)
				(type default)
			)
			(layer "F.Fab")
		)
		(fp_line
			(start -0.299974 0.150114)
			(end -0.299974 -0.150114)
			(stroke
				(width 0.1)
				(type default)
			)
			(layer "F.Fab")
		)
		(fp_line
			(start -0.299974 -0.150114)
			(end 0.299974 -0.150114)
			(stroke
				(width 0.1)
				(type default)
			)
			(layer "F.Fab")
		)
		(pad "1" smd rect
			(at -0.2667 0 180)
			(size 0.3048 0.381)
			(layers "F.Cu" "F.Mask" "F.Paste")
			(net "P3E_PCH_E1S_TX_DN<1>")
		)
		(pad "2" smd rect
			(at 0.2667 0 180)
			(size 0.3048 0.381)
			(layers "F.Cu" "F.Mask" "F.Paste")
			(net "P3E_PCH_E1S_TX_C_DN<1>")
		)
		(zone
			(layer "In1.Cu")
			(hatch none 0.5)
			(connect_pads
				(clearance 0)
			)
			(min_thickness 0.25)
			(keepout
				(tracks not_allowed)
				(vias allowed)
				(pads allowed)
				(copperpour not_allowed)
				(footprints allowed)
			)
			(placement
				(enabled no)
				(sheetname "")
			)
			(fill
				(thermal_gap 0.5)
				(thermal_bridge_width 0.5)
				(island_removal_mode 0)
			)
			(polygon
				(pts
					(arc
						(start 239.012984 -54.976522)
						(mid 239.066866 -54.954204)
						(end 239.089184 -54.900322)
					)
					(arc
						(start 239.089184 -54.570122)
						(mid 239.066866 -54.51624)
						(end 239.012984 -54.493922)
					)
					(arc
						(start 238.758984 -54.493922)
						(mid 238.705102 -54.51624)
						(end 238.682784 -54.570122)
					)
					(arc
						(start 238.682784 -54.900322)
						(mid 238.705102 -54.954204)
						(end 238.758984 -54.976522)
					)
				)
			)
		)
		(zone
			(layer "In1.Cu")
			(hatch none 0.5)
			(connect_pads
				(clearance 0)
			)
			(min_thickness 0.25)
			(keepout
				(tracks not_allowed)
				(vias allowed)
				(pads allowed)
				(copperpour not_allowed)
				(footprints allowed)
			)
			(placement
				(enabled no)
				(sheetname "")
			)
			(fill
				(thermal_gap 0.5)
				(thermal_bridge_width 0.5)
				(island_removal_mode 0)
			)
			(polygon
				(pts
					(arc
						(start 239.546384 -54.976522)
						(mid 239.600266 -54.954204)
						(end 239.622584 -54.900322)
					)
					(arc
						(start 239.622584 -54.570122)
						(mid 239.600266 -54.51624)
						(end 239.546384 -54.493922)
					)
					(arc
						(start 239.292384 -54.493922)
						(mid 239.238502 -54.51624)
						(end 239.216184 -54.570122)
					)
					(arc
						(start 239.216184 -54.900322)
						(mid 239.238502 -54.954204)
						(end 239.292384 -54.976522)
					)
				)
			)
		)
	)
	(footprint ""
		(layer "F.Cu")
		(at 278.474678 -420.6113 90)
		(property "Reference" "U369"
			(at -1.6002 3.870452 90)
			(unlocked yes)
			(layer "F.SilkS")
			(effects
				(font
					(size 0.7874 0.5842)
					(thickness 0.1524)
				)
				(justify left)
			)
		)
		(property "Value" ""
			(at 0 0 90)
			(layer "F.Fab")
			(effects
				(font
					(size 1.27 1.27)
				)
			)
		)
		(duplicate_pad_numbers_are_jumpers no)
		(fp_line
			(start 2.03581 -1.525016)
			(end 0.82423 -1.525016)
			(stroke
				(width 0.1524)
				(type default)
			)
			(layer "F.SilkS")
		)
		(fp_line
			(start 0.82423 -1.525016)
			(end 0 -0.649986)
			(stroke
				(width 0.1524)
				(type default)
			)
			(layer "F.SilkS")
		)
		(fp_line
			(start -0.82423 -1.525016)
			(end -2.03581 -1.525016)
			(stroke
				(width 0.1524)
				(type default)
			)
			(layer "F.SilkS")
		)
		(fp_line
			(start -2.03581 -1.525016)
			(end -2.03581 1.525016)
			(stroke
				(width 0.1524)
				(type default)
			)
			(layer "F.SilkS")
		)
		(fp_line
			(start 0 -0.649986)
			(end -0.82423 -1.525016)
			(stroke
				(width 0.1524)
				(type default)
			)
			(layer "F.SilkS")
		)
		(fp_line
			(start 2.03581 1.525016)
			(end 2.03581 -1.525016)
			(stroke
				(width 0.1524)
				(type default)
			)
			(layer "F.SilkS")
		)
		(fp_line
			(start -2.03581 1.525016)
			(end 2.03581 1.525016)
			(stroke
				(width 0.1524)
				(type default)
			)
			(layer "F.SilkS")
		)
		(fp_poly
			(pts
				(xy -1.501902 -1.539748) (xy -1.886458 -2.309368) (xy -1.117092 -2.309368)
			)
			(stroke
				(width 0)
				(type default)
			)
			(fill yes)
			(layer "F.SilkS")
		)
		(fp_line
			(start 0.87503 -1.525016)
			(end -0.87503 -1.525016)
			(stroke
				(width 0.1)
				(type default)
			)
			(layer "F.Fab")
		)
		(fp_line
			(start -0.87503 -1.525016)
			(end -0.87503 1.525016)
			(stroke
				(width 0.1)
				(type default)
			)
			(layer "F.Fab")
		)
		(fp_line
			(start 0.87503 1.525016)
			(end 0.87503 -1.525016)
			(stroke
				(width 0.1)
				(type default)
			)
			(layer "F.Fab")
		)
		(fp_line
			(start -0.87503 1.525016)
			(end 0.87503 1.525016)
			(stroke
				(width 0.1)
				(type default)
			)
			(layer "F.Fab")
		)
		(fp_poly
			(pts
				(xy -2.12979 -0.943356) (xy -2.89941 -0.5588) (xy -2.89941 -1.328166)
			)
			(stroke
				(width 0)
				(type default)
			)
			(fill yes)
			(layer "F.Fab")
		)
		(pad "1" smd rect
			(at -1.35001 -0.94996)
			(size 0.6096 1.1176)
			(layers "F.Cu" "F.Mask" "F.Paste")
			(net "A_HSC_LOW_GATE")
		)
		(pad "2" smd rect
			(at -1.35001 0)
			(size 0.6096 1.1176)
			(layers "F.Cu" "F.Mask" "F.Paste")
			(net "GND")
		)
		(pad "3" smd rect
			(at -1.35001 0.94996)
			(size 0.6096 1.1176)
			(layers "F.Cu" "F.Mask" "F.Paste")
			(net "A_HSC_LOW")
		)
		(pad "4" smd rect
			(at 1.35001 0.94996)
			(size 0.6096 1.1176)
			(layers "F.Cu" "F.Mask" "F.Paste")
			(net "A_HSC_HIGH")
		)
		(pad "5" smd rect
			(at 1.35001 0)
			(size 0.6096 1.1176)
			(layers "F.Cu" "F.Mask" "F.Paste")
			(net "U369_VDD")
		)
		(pad "6" smd rect
			(at 1.35001 -0.94996)
			(size 0.6096 1.1176)
			(layers "F.Cu" "F.Mask" "F.Paste")
			(net "HSC_D_OC")
		)
	)
)
